FILE_TYPE=LIBRARY_PARTS;
primitive 'DIODE','DIODE_SM','DIODE_SMLF';
  pin
    'C':
      PIN_NUMBER='(1)';
      PINUSE='UNSPEC';
      NO_LOAD_CHECK='BOTH';
      NO_IO_CHECK='BOTH';
      ALLOW_CONNECT='TRUE';
    'A':
      PIN_NUMBER='(2)';
      PINUSE='UNSPEC';
      NO_LOAD_CHECK='BOTH';
      NO_IO_CHECK='BOTH';
      ALLOW_CONNECT='TRUE';
  end_pin;
  body    
    PART_NAME='DIODE';
    PHYS_DES_PREFIX='CR';
  end_body;
end_primitive;
primitive 'DIODE_SOT23';
  pin
    'C':
      PIN_NUMBER='(3)';
      PINUSE='UNSPEC';
      NO_LOAD_CHECK='BOTH';
      NO_IO_CHECK='BOTH';
      ALLOW_CONNECT='TRUE';
    'A':
      PIN_NUMBER='(1)';
      PINUSE='UNSPEC';
      NO_LOAD_CHECK='BOTH';
      NO_IO_CHECK='BOTH';
      ALLOW_CONNECT='TRUE';
  end_pin;
  body
    NC_PINS='(2)';
    PART_NAME='DIODE';
    PHYS_DES_PREFIX='CR';
  end_body;
end_primitive;
primitive 'DIODE_SOT23LF';
  pin
    'C':
      PIN_NUMBER='(3)';
      PINUSE='UNSPEC';
      NO_LOAD_CHECK='BOTH';
      NO_IO_CHECK='BOTH';
      ALLOW_CONNECT='TRUE';
    'A':
      PIN_NUMBER='(1)';
      PINUSE='UNSPEC';
      NO_LOAD_CHECK='BOTH';
      NO_IO_CHECK='BOTH';
      ALLOW_CONNECT='TRUE';
  end_pin;
  body
    NC_PINS='(2)';
    PART_NAME='DIODE';
    PHYS_DES_PREFIX='CR';
  end_body;
end_primitive;
primitive 'DIODE_4036ALF';
  pin
    'C':
      PIN_NUMBER='(2)';
      PINUSE='UNSPEC';
      NO_LOAD_CHECK='BOTH';
      NO_IO_CHECK='BOTH';
      ALLOW_CONNECT='TRUE';
    'A':
      PIN_NUMBER='(3)';
      PINUSE='UNSPEC';
      NO_LOAD_CHECK='BOTH';
      NO_IO_CHECK='BOTH';
      ALLOW_CONNECT='TRUE';
  end_pin;
  body
    NC_PINS='(1)';
    PART_NAME='DIODE';
    PHYS_DES_PREFIX='CR';
  end_body;
end_primitive;
primitive 'DIODE_SDPAKLF';
  pin
    'C':
      PIN_NUMBER='(2)';
      PINUSE='UNSPEC';
      NO_LOAD_CHECK='BOTH';
      NO_IO_CHECK='BOTH';
      ALLOW_CONNECT='TRUE';
    'A':
      PIN_NUMBER='(1)';
      PINUSE='UNSPEC';
      NO_LOAD_CHECK='BOTH';
      NO_IO_CHECK='BOTH';
      ALLOW_CONNECT='TRUE';
  end_pin;
  body
    NC_PINS='(3)';
    PART_NAME='DIODE';
    PHYS_DES_PREFIX='CR';
  end_body;
end_primitive;
primitive 'DIODE_SOD';
  pin
    'C':
      PIN_NUMBER='(2)';
      PINUSE='UNSPEC';
      NO_LOAD_CHECK='BOTH';
      NO_IO_CHECK='BOTH';
      ALLOW_CONNECT='TRUE';
    'A':
      PIN_NUMBER='(1)';
      PINUSE='UNSPEC';
      NO_LOAD_CHECK='BOTH';
      NO_IO_CHECK='BOTH';
      ALLOW_CONNECT='TRUE';
  end_pin;
  body    
    PART_NAME='DIODE';
    PHYS_DES_PREFIX='CR';
  end_body;
end_primitive;

END.
